(kicad_pcb
	(version 20260206)
	(generator "pcbnew")
	(generator_version "10.0")
	(general
		(thickness 1.6)
		(legacy_teardrops no)
	)
	(paper "A4")
	(title_block
		(title "04192023_DAF0TMB3IC0_F0TG_MB_C_brd_V02_OCP.brd")
		(comment 1 "Grand Teton / footprints 3103-3109 of 8354")
	)
	(layers
		(0 "F.Cu" signal "TOP")
		(4 "In1.Cu" signal "GND")
		(6 "In2.Cu" signal "IN1")
		(8 "In3.Cu" signal "GND1")
		(10 "In4.Cu" signal "IN2")
		(12 "In5.Cu" signal "GND2")
		(14 "In6.Cu" signal "IN3")
		(16 "In7.Cu" signal "GND3")
		(18 "In8.Cu" signal "VCC")
		(20 "In9.Cu" signal "VCC1")
		(22 "In10.Cu" signal "GND4")
		(24 "In11.Cu" signal "IN4")
		(26 "In12.Cu" signal "GND5")
		(28 "In13.Cu" signal "IN5")
		(30 "In14.Cu" signal "GND6")
		(32 "In15.Cu" signal "IN6")
		(34 "In16.Cu" signal "GND7")
		(2 "B.Cu" signal "BOTTOM")
		(9 "F.Adhes" user "F.Adhesive")
		(11 "B.Adhes" user "B.Adhesive")
		(13 "F.Paste" user "Package Geometry/Pastemask Top")
		(15 "B.Paste" user "Package Geometry/Pastemask Bottom")
		(5 "F.SilkS" user "Ref Des/Silkscreen Top")
		(7 "B.SilkS" user "Ref Des/Silkscreen Bottom")
		(1 "F.Mask" user "Board Geometry/Soldermask Top")
		(3 "B.Mask" user "Board Geometry/Soldermask Bottom")
		(17 "Dwgs.User" user "User.Drawings")
		(19 "Cmts.User" user "User.Comments")
		(21 "Eco1.User" user "User.Eco1")
		(23 "Eco2.User" user "User.Eco2")
		(25 "Edge.Cuts" user "Board Geometry/Outline")
		(27 "Margin" user)
		(31 "F.CrtYd" user "Package Geometry/Place Bound Top")
		(29 "B.CrtYd" user "Package Geometry/Place Bound Bottom")
		(35 "F.Fab" user "Ref Des/Assembly Top")
		(33 "B.Fab" user "Ref Des/Assembly Bottom")
	)
	(footprint ""
		(layer "F.Cu")
		(at 102.390194 -384.10388 180)
		(property "Reference" "R653"
			(at 0 0 180)
			(layer "F.SilkS")
			(hide yes)
			(effects
				(font
					(size 1.27 1.27)
				)
			)
		)
		(property "Value" ""
			(at 0 0 180)
			(layer "F.Fab")
			(effects
				(font
					(size 1.27 1.27)
				)
			)
		)
		(duplicate_pad_numbers_are_jumpers no)
		(fp_line
			(start 0.7874 0.4064)
			(end -0.7874 0.4064)
			(stroke
				(width 0.1524)
				(type default)
			)
			(layer "F.SilkS")
		)
		(fp_line
			(start 0.7874 -0.4064)
			(end 0.7874 0.4064)
			(stroke
				(width 0.1524)
				(type default)
			)
			(layer "F.SilkS")
		)
		(fp_line
			(start -0.7874 0.4064)
			(end -0.7874 -0.4064)
			(stroke
				(width 0.1524)
				(type default)
			)
			(layer "F.SilkS")
		)
		(fp_line
			(start -0.7874 -0.4064)
			(end 0.7874 -0.4064)
			(stroke
				(width 0.1524)
				(type default)
			)
			(layer "F.SilkS")
		)
		(fp_line
			(start 0.67945 0.3048)
			(end 0.120396 0.3048)
			(stroke
				(width 0.1)
				(type default)
			)
			(layer "F.Fab")
		)
		(fp_line
			(start 0.67945 -0.3048)
			(end 0.67945 0.3048)
			(stroke
				(width 0.1)
				(type default)
			)
			(layer "F.Fab")
		)
		(fp_line
			(start 0.12065 -0.2794)
			(end 0.12065 -0.3048)
			(stroke
				(width 0.1)
				(type default)
			)
			(layer "F.Fab")
		)
		(fp_line
			(start 0.12065 -0.3048)
			(end 0.67945 -0.3048)
			(stroke
				(width 0.1)
				(type default)
			)
			(layer "F.Fab")
		)
		(fp_line
			(start 0.120396 0.3048)
			(end 0.120396 0.2794)
			(stroke
				(width 0.1)
				(type default)
			)
			(layer "F.Fab")
		)
		(fp_line
			(start 0.120396 0.2794)
			(end -0.12065 0.2794)
			(stroke
				(width 0.1)
				(type default)
			)
			(layer "F.Fab")
		)
		(fp_line
			(start -0.12065 0.3048)
			(end -0.67945 0.3048)
			(stroke
				(width 0.1)
				(type default)
			)
			(layer "F.Fab")
		)
		(fp_line
			(start -0.12065 0.2794)
			(end -0.12065 0.3048)
			(stroke
				(width 0.1)
				(type default)
			)
			(layer "F.Fab")
		)
		(fp_line
			(start -0.12065 -0.2794)
			(end 0.12065 -0.2794)
			(stroke
				(width 0.1)
				(type default)
			)
			(layer "F.Fab")
		)
		(fp_line
			(start -0.12065 -0.305054)
			(end -0.12065 -0.2794)
			(stroke
				(width 0.1)
				(type default)
			)
			(layer "F.Fab")
		)
		(fp_line
			(start -0.67945 0.3048)
			(end -0.67945 -0.305054)
			(stroke
				(width 0.1)
				(type default)
			)
			(layer "F.Fab")
		)
		(fp_line
			(start -0.67945 -0.305054)
			(end -0.12065 -0.305054)
			(stroke
				(width 0.1)
				(type default)
			)
			(layer "F.Fab")
		)
		(pad "1" smd rect
			(at -0.40005 0)
			(size 0.4572 0.508)
			(layers "F.Cu" "F.Mask" "F.Paste")
			(net "P1V8_CPU1_RT1_1A_1D")
		)
		(pad "2" smd rect
			(at 0.40005 0)
			(size 0.4572 0.508)
			(layers "F.Cu" "F.Mask" "F.Paste")
			(net "P1V8_CPU1_RT1_1A")
		)
	)
	(footprint ""
		(layer "F.Cu")
		(at 391.291318 -78.439264)
		(property "Reference" "R1320"
			(at 0 0 0)
			(layer "F.SilkS")
			(hide yes)
			(effects
				(font
					(size 1.27 1.27)
				)
			)
		)
		(property "Value" ""
			(at 0 0 0)
			(layer "F.Fab")
			(effects
				(font
					(size 1.27 1.27)
				)
			)
		)
		(duplicate_pad_numbers_are_jumpers no)
		(fp_line
			(start -0.7874 -0.4064)
			(end 0.7874 -0.4064)
			(stroke
				(width 0.1524)
				(type default)
			)
			(layer "F.SilkS")
		)
		(fp_line
			(start -0.7874 0.4064)
			(end -0.7874 -0.4064)
			(stroke
				(width 0.1524)
				(type default)
			)
			(layer "F.SilkS")
		)
		(fp_line
			(start 0.7874 -0.4064)
			(end 0.7874 0.4064)
			(stroke
				(width 0.1524)
				(type default)
			)
			(layer "F.SilkS")
		)
		(fp_line
			(start 0.7874 0.4064)
			(end -0.7874 0.4064)
			(stroke
				(width 0.1524)
				(type default)
			)
			(layer "F.SilkS")
		)
		(fp_line
			(start -0.67945 -0.305054)
			(end -0.12065 -0.305054)
			(stroke
				(width 0.1)
				(type default)
			)
			(layer "F.Fab")
		)
		(fp_line
			(start -0.67945 0.3048)
			(end -0.67945 -0.305054)
			(stroke
				(width 0.1)
				(type default)
			)
			(layer "F.Fab")
		)
		(fp_line
			(start -0.12065 -0.305054)
			(end -0.12065 -0.2794)
			(stroke
				(width 0.1)
				(type default)
			)
			(layer "F.Fab")
		)
		(fp_line
			(start -0.12065 -0.2794)
			(end 0.12065 -0.2794)
			(stroke
				(width 0.1)
				(type default)
			)
			(layer "F.Fab")
		)
		(fp_line
			(start -0.12065 0.2794)
			(end -0.12065 0.3048)
			(stroke
				(width 0.1)
				(type default)
			)
			(layer "F.Fab")
		)
		(fp_line
			(start -0.12065 0.3048)
			(end -0.67945 0.3048)
			(stroke
				(width 0.1)
				(type default)
			)
			(layer "F.Fab")
		)
		(fp_line
			(start 0.120396 0.2794)
			(end -0.12065 0.2794)
			(stroke
				(width 0.1)
				(type default)
			)
			(layer "F.Fab")
		)
		(fp_line
			(start 0.120396 0.3048)
			(end 0.120396 0.2794)
			(stroke
				(width 0.1)
				(type default)
			)
			(layer "F.Fab")
		)
		(fp_line
			(start 0.12065 -0.3048)
			(end 0.67945 -0.3048)
			(stroke
				(width 0.1)
				(type default)
			)
			(layer "F.Fab")
		)
		(fp_line
			(start 0.12065 -0.2794)
			(end 0.12065 -0.3048)
			(stroke
				(width 0.1)
				(type default)
			)
			(layer "F.Fab")
		)
		(fp_line
			(start 0.67945 -0.3048)
			(end 0.67945 0.3048)
			(stroke
				(width 0.1)
				(type default)
			)
			(layer "F.Fab")
		)
		(fp_line
			(start 0.67945 0.3048)
			(end 0.120396 0.3048)
			(stroke
				(width 0.1)
				(type default)
			)
			(layer "F.Fab")
		)
		(pad "1" smd circle
			(at -0.40005 0)
			(size 0 0)
			(layers "F.Cu" "F.Mask" "F.Paste")
			(net "P3V3_AUX")
		)
		(pad "2" smd circle
			(at 0.40005 0)
			(size 0 0)
			(layers "F.Cu" "F.Mask" "F.Paste")
			(net "INA230_6_A1")
		)
	)
	(footprint ""
		(layer "F.Cu")
		(at 103.819706 -178.077876 90)
		(property "Reference" "PC291_4"
			(at 0 0 90)
			(layer "F.SilkS")
			(hide yes)
			(effects
				(font
					(size 1.27 1.27)
				)
			)
		)
		(property "Value" ""
			(at 0 0 90)
			(layer "F.Fab")
			(effects
				(font
					(size 1.27 1.27)
				)
			)
		)
		(duplicate_pad_numbers_are_jumpers no)
		(fp_line
			(start 0.7874 -0.4064)
			(end 0.7874 0.4064)
			(stroke
				(width 0.1524)
				(type default)
			)
			(layer "F.SilkS")
		)
		(fp_line
			(start -0.7874 -0.4064)
			(end 0.7874 -0.4064)
			(stroke
				(width 0.1524)
				(type default)
			)
			(layer "F.SilkS")
		)
		(fp_line
			(start 0.7874 0.4064)
			(end -0.7874 0.4064)
			(stroke
				(width 0.1524)
				(type default)
			)
			(layer "F.SilkS")
		)
		(fp_line
			(start -0.7874 0.4064)
			(end -0.7874 -0.4064)
			(stroke
				(width 0.1524)
				(type default)
			)
			(layer "F.SilkS")
		)
		(fp_line
			(start -0.12065 -0.305054)
			(end -0.12065 -0.2794)
			(stroke
				(width 0.1)
				(type default)
			)
			(layer "F.Fab")
		)
		(fp_line
			(start -0.67945 -0.305054)
			(end -0.12065 -0.305054)
			(stroke
				(width 0.1)
				(type default)
			)
			(layer "F.Fab")
		)
		(fp_line
			(start 0.67945 -0.3048)
			(end 0.67945 0.3048)
			(stroke
				(width 0.1)
				(type default)
			)
			(layer "F.Fab")
		)
		(fp_line
			(start 0.12065 -0.3048)
			(end 0.67945 -0.3048)
			(stroke
				(width 0.1)
				(type default)
			)
			(layer "F.Fab")
		)
		(fp_line
			(start 0.12065 -0.2794)
			(end 0.12065 -0.3048)
			(stroke
				(width 0.1)
				(type default)
			)
			(layer "F.Fab")
		)
		(fp_line
			(start -0.12065 -0.2794)
			(end 0.12065 -0.2794)
			(stroke
				(width 0.1)
				(type default)
			)
			(layer "F.Fab")
		)
		(fp_line
			(start 0.120396 0.2794)
			(end -0.12065 0.2794)
			(stroke
				(width 0.1)
				(type default)
			)
			(layer "F.Fab")
		)
		(fp_line
			(start -0.12065 0.2794)
			(end -0.12065 0.3048)
			(stroke
				(width 0.1)
				(type default)
			)
			(layer "F.Fab")
		)
		(fp_line
			(start 0.67945 0.3048)
			(end 0.120396 0.3048)
			(stroke
				(width 0.1)
				(type default)
			)
			(layer "F.Fab")
		)
		(fp_line
			(start 0.120396 0.3048)
			(end 0.120396 0.2794)
			(stroke
				(width 0.1)
				(type default)
			)
			(layer "F.Fab")
		)
		(fp_line
			(start -0.12065 0.3048)
			(end -0.67945 0.3048)
			(stroke
				(width 0.1)
				(type default)
			)
			(layer "F.Fab")
		)
		(fp_line
			(start -0.67945 0.3048)
			(end -0.67945 -0.305054)
			(stroke
				(width 0.1)
				(type default)
			)
			(layer "F.Fab")
		)
		(pad "1" smd circle
			(at -0.40005 0 90)
			(size 0 0)
			(layers "F.Cu" "F.Mask" "F.Paste")
			(net "SW_P12V_AUX_PVDDCR_CPU0_P1_FLT")
		)
		(pad "2" smd circle
			(at 0.40005 0 90)
			(size 0 0)
			(layers "F.Cu" "F.Mask" "F.Paste")
			(net "GND")
		)
	)
	(footprint ""
		(layer "F.Cu")
		(at 49.407318 -351.10547)
		(property "Reference" "PC438_1"
			(at 0 0 0)
			(layer "F.SilkS")
			(hide yes)
			(effects
				(font
					(size 1.27 1.27)
				)
			)
		)
		(property "Value" ""
			(at 0 0 0)
			(layer "F.Fab")
			(effects
				(font
					(size 1.27 1.27)
				)
			)
		)
		(duplicate_pad_numbers_are_jumpers no)
		(fp_line
			(start -0.7874 -0.4064)
			(end 0.7874 -0.4064)
			(stroke
				(width 0.1524)
				(type default)
			)
			(layer "F.SilkS")
		)
		(fp_line
			(start -0.7874 0.4064)
			(end -0.7874 -0.4064)
			(stroke
				(width 0.1524)
				(type default)
			)
			(layer "F.SilkS")
		)
		(fp_line
			(start 0.7874 -0.4064)
			(end 0.7874 0.4064)
			(stroke
				(width 0.1524)
				(type default)
			)
			(layer "F.SilkS")
		)
		(fp_line
			(start 0.7874 0.4064)
			(end -0.7874 0.4064)
			(stroke
				(width 0.1524)
				(type default)
			)
			(layer "F.SilkS")
		)
		(fp_line
			(start -0.67945 -0.305054)
			(end -0.12065 -0.305054)
			(stroke
				(width 0.1)
				(type default)
			)
			(layer "F.Fab")
		)
		(fp_line
			(start -0.67945 0.3048)
			(end -0.67945 -0.305054)
			(stroke
				(width 0.1)
				(type default)
			)
			(layer "F.Fab")
		)
		(fp_line
			(start -0.12065 -0.305054)
			(end -0.12065 -0.2794)
			(stroke
				(width 0.1)
				(type default)
			)
			(layer "F.Fab")
		)
		(fp_line
			(start -0.12065 -0.2794)
			(end 0.12065 -0.2794)
			(stroke
				(width 0.1)
				(type default)
			)
			(layer "F.Fab")
		)
		(fp_line
			(start -0.12065 0.2794)
			(end -0.12065 0.3048)
			(stroke
				(width 0.1)
				(type default)
			)
			(layer "F.Fab")
		)
		(fp_line
			(start -0.12065 0.3048)
			(end -0.67945 0.3048)
			(stroke
				(width 0.1)
				(type default)
			)
			(layer "F.Fab")
		)
		(fp_line
			(start 0.120396 0.2794)
			(end -0.12065 0.2794)
			(stroke
				(width 0.1)
				(type default)
			)
			(layer "F.Fab")
		)
		(fp_line
			(start 0.120396 0.3048)
			(end 0.120396 0.2794)
			(stroke
				(width 0.1)
				(type default)
			)
			(layer "F.Fab")
		)
		(fp_line
			(start 0.12065 -0.3048)
			(end 0.67945 -0.3048)
			(stroke
				(width 0.1)
				(type default)
			)
			(layer "F.Fab")
		)
		(fp_line
			(start 0.12065 -0.2794)
			(end 0.12065 -0.3048)
			(stroke
				(width 0.1)
				(type default)
			)
			(layer "F.Fab")
		)
		(fp_line
			(start 0.67945 -0.3048)
			(end 0.67945 0.3048)
			(stroke
				(width 0.1)
				(type default)
			)
			(layer "F.Fab")
		)
		(fp_line
			(start 0.67945 0.3048)
			(end 0.120396 0.3048)
			(stroke
				(width 0.1)
				(type default)
			)
			(layer "F.Fab")
		)
		(pad "1" smd circle
			(at -0.40005 0)
			(size 0 0)
			(layers "F.Cu" "F.Mask" "F.Paste")
			(net "SW_P12V_AUX_PVDDIO_P1_FLT")
		)
		(pad "2" smd circle
			(at 0.40005 0)
			(size 0 0)
			(layers "F.Cu" "F.Mask" "F.Paste")
			(net "GND")
		)
	)
	(footprint ""
		(layer "F.Cu")
		(at 393.363958 -324.659752)
		(property "Reference" "R450"
			(at 0 0 0)
			(layer "F.SilkS")
			(hide yes)
			(effects
				(font
					(size 1.27 1.27)
				)
			)
		)
		(property "Value" ""
			(at 0 0 0)
			(layer "F.Fab")
			(effects
				(font
					(size 1.27 1.27)
				)
			)
		)
		(duplicate_pad_numbers_are_jumpers no)
		(fp_line
			(start -0.7874 -0.4064)
			(end 0.7874 -0.4064)
			(stroke
				(width 0.1524)
				(type default)
			)
			(layer "F.SilkS")
		)
		(fp_line
			(start -0.7874 0.4064)
			(end -0.7874 -0.4064)
			(stroke
				(width 0.1524)
				(type default)
			)
			(layer "F.SilkS")
		)
		(fp_line
			(start 0.7874 -0.4064)
			(end 0.7874 0.4064)
			(stroke
				(width 0.1524)
				(type default)
			)
			(layer "F.SilkS")
		)
		(fp_line
			(start 0.7874 0.4064)
			(end -0.7874 0.4064)
			(stroke
				(width 0.1524)
				(type default)
			)
			(layer "F.SilkS")
		)
		(fp_line
			(start -0.67945 -0.305054)
			(end -0.12065 -0.305054)
			(stroke
				(width 0.1)
				(type default)
			)
			(layer "F.Fab")
		)
		(fp_line
			(start -0.67945 0.3048)
			(end -0.67945 -0.305054)
			(stroke
				(width 0.1)
				(type default)
			)
			(layer "F.Fab")
		)
		(fp_line
			(start -0.12065 -0.305054)
			(end -0.12065 -0.2794)
			(stroke
				(width 0.1)
				(type default)
			)
			(layer "F.Fab")
		)
		(fp_line
			(start -0.12065 -0.2794)
			(end 0.12065 -0.2794)
			(stroke
				(width 0.1)
				(type default)
			)
			(layer "F.Fab")
		)
		(fp_line
			(start -0.12065 0.2794)
			(end -0.12065 0.3048)
			(stroke
				(width 0.1)
				(type default)
			)
			(layer "F.Fab")
		)
		(fp_line
			(start -0.12065 0.3048)
			(end -0.67945 0.3048)
			(stroke
				(width 0.1)
				(type default)
			)
			(layer "F.Fab")
		)
		(fp_line
			(start 0.120396 0.2794)
			(end -0.12065 0.2794)
			(stroke
				(width 0.1)
				(type default)
			)
			(layer "F.Fab")
		)
		(fp_line
			(start 0.120396 0.3048)
			(end 0.120396 0.2794)
			(stroke
				(width 0.1)
				(type default)
			)
			(layer "F.Fab")
		)
		(fp_line
			(start 0.12065 -0.3048)
			(end 0.67945 -0.3048)
			(stroke
				(width 0.1)
				(type default)
			)
			(layer "F.Fab")
		)
		(fp_line
			(start 0.12065 -0.2794)
			(end 0.12065 -0.3048)
			(stroke
				(width 0.1)
				(type default)
			)
			(layer "F.Fab")
		)
		(fp_line
			(start 0.67945 -0.3048)
			(end 0.67945 0.3048)
			(stroke
				(width 0.1)
				(type default)
			)
			(layer "F.Fab")
		)
		(fp_line
			(start 0.67945 0.3048)
			(end 0.120396 0.3048)
			(stroke
				(width 0.1)
				(type default)
			)
			(layer "F.Fab")
		)
		(pad "1" smd circle
			(at -0.40005 0)
			(size 0 0)
			(layers "F.Cu" "F.Mask" "F.Paste")
			(net "CPU0_SMERR_N")
		)
		(pad "2" smd circle
			(at 0.40005 0)
			(size 0 0)
			(layers "F.Cu" "F.Mask" "F.Paste")
			(net "PVDD18_S5_P0")
		)
	)
	(footprint ""
		(layer "F.Cu")
		(at 141.197838 -167.03167)
		(property "Reference" "TP11"
			(at 1.13792 -0.014732 0)
			(unlocked yes)
			(layer "F.SilkS")
			(effects
				(font
					(size 0.7874 0.5842)
					(thickness 0.1524)
				)
				(justify left)
			)
		)
		(property "Value" ""
			(at 0 0 0)
			(layer "F.Fab")
			(effects
				(font
					(size 1.27 1.27)
				)
			)
		)
		(duplicate_pad_numbers_are_jumpers no)
		(pad "1" smd circle
			(at 0 0)
			(size 0.762 0.762)
			(layers "F.Cu" "F.Mask" "F.Paste")
			(net "VSENSE_VSS_SENSE_A_P1")
		)
	)
	(footprint ""
		(layer "F.Cu")
		(at 112.72774 -394.166852 -90)
		(property "Reference" "R926"
			(at 0 0 270)
			(layer "F.SilkS")
			(hide yes)
			(effects
				(font
					(size 1.27 1.27)
				)
			)
		)
		(property "Value" ""
			(at 0 0 270)
			(layer "F.Fab")
			(effects
				(font
					(size 1.27 1.27)
				)
			)
		)
		(duplicate_pad_numbers_are_jumpers no)
		(fp_line
			(start -0.32512 0.175006)
			(end -0.32512 -0.175006)
			(stroke
				(width 0.1)
				(type default)
			)
			(layer "F.Fab")
		)
		(fp_line
			(start 0.32512 0.175006)
			(end -0.32512 0.175006)
			(stroke
				(width 0.1)
				(type default)
			)
			(layer "F.Fab")
		)
		(fp_line
			(start -0.32512 -0.175006)
			(end 0.32512 -0.175006)
			(stroke
				(width 0.1)
				(type default)
			)
			(layer "F.Fab")
		)
		(fp_line
			(start 0.32512 -0.175006)
			(end 0.32512 0.175006)
			(stroke
				(width 0.1)
				(type default)
			)
			(layer "F.Fab")
		)
		(pad "1" smd rect
			(at -0.2667 0 270)
			(size 0.3048 0.381)
			(layers "F.Cu" "F.Mask" "F.Paste")
			(net "MODE_RT_CPU1_P3")
		)
		(pad "2" smd rect
			(at 0.2667 0 90)
			(size 0.3048 0.381)
			(layers "F.Cu" "F.Mask" "F.Paste")
			(net "GND")
		)
	)
)
